(kicad_pcb
	(version 20260206)
	(generator "pcbnew")
	(generator_version "10.0")
	(general
		(thickness 1.6)
		(legacy_teardrops no)
	)
	(paper "A4")
	(title_block
		(title "v1-pdb — T6M_PDB_D_0927_0900.brd")
		(comment 1 "Open CloudServer (Microsoft) / footprints 89-89 of 321")
	)
	(layers
		(0 "F.Cu" signal "TOP")
		(4 "In1.Cu" signal "GND")
		(6 "In2.Cu" signal "IN1")
		(8 "In3.Cu" signal "VCC")
		(10 "In4.Cu" signal "VCC1")
		(12 "In5.Cu" signal "IN2")
		(14 "In6.Cu" signal "GND1")
		(2 "B.Cu" signal "BOTTOM")
		(9 "F.Adhes" user "F.Adhesive")
		(11 "B.Adhes" user "B.Adhesive")
		(13 "F.Paste" user "Package Geometry/Pastemask Top")
		(15 "B.Paste" user "Package Geometry/Pastemask Bottom")
		(5 "F.SilkS" user "Ref Des/Silkscreen Top")
		(7 "B.SilkS" user "Ref Des/Silkscreen Bottom")
		(1 "F.Mask" user "Board Geometry/Soldermask Top")
		(3 "B.Mask" user "Board Geometry/Soldermask Bottom")
		(17 "Dwgs.User" user "User.Drawings")
		(19 "Cmts.User" user "User.Comments")
		(21 "Eco1.User" user "User.Eco1")
		(23 "Eco2.User" user "User.Eco2")
		(25 "Edge.Cuts" user "Board Geometry/Outline")
		(27 "Margin" user)
		(31 "F.CrtYd" user "Package Geometry/Place Bound Top")
		(29 "B.CrtYd" user "Package Geometry/Place Bound Bottom")
		(35 "F.Fab" user "Ref Des/Assembly Top")
		(33 "B.Fab" user "Ref Des/Assembly Bottom")
	)
	(footprint ""
		(layer "F.Cu")
		(at 30.45968 -348.52991)
		(property "Reference" "J4"
			(at 7.95274 12.227052 0)
			(unlocked yes)
			(layer "F.SilkS")
			(effects
				(font
					(size 0.7874 0.5842)
					(thickness 0.1524)
				)
				(justify left)
			)
		)
		(property "Value" ""
			(at 0 0 0)
			(layer "F.Fab")
			(effects
				(font
					(size 1.27 1.27)
				)
			)
		)
		(duplicate_pad_numbers_are_jumpers no)
		(fp_line
			(start -2.135124 -4.560062)
			(end -2.135124 83.300062)
			(stroke
				(width 0.1524)
				(type default)
			)
			(layer "F.SilkS")
		)
		(fp_line
			(start -2.135124 83.300062)
			(end 7.215124 83.300062)
			(stroke
				(width 0.1524)
				(type default)
			)
			(layer "F.SilkS")
		)
		(fp_line
			(start 7.215124 -4.560062)
			(end -2.135124 -4.560062)
			(stroke
				(width 0.1524)
				(type default)
			)
			(layer "F.SilkS")
		)
		(fp_line
			(start 7.215124 83.300062)
			(end 7.215124 -4.560062)
			(stroke
				(width 0.1524)
				(type default)
			)
			(layer "F.SilkS")
		)
		(fp_poly
			(pts
				(xy -2.422398 -0.000762) (xy -5.122418 -0.700786) (xy -5.122418 0.699262)
			)
			(stroke
				(width 0)
				(type default)
			)
			(fill yes)
			(layer "F.SilkS")
		)
		(fp_poly
			(pts
				(xy -2.28219 -0.127) (xy -4.98221 -0.827024) (xy -4.98221 0.573024)
			)
			(stroke
				(width 0)
				(type default)
			)
			(fill yes)
			(layer "B.SilkS")
		)
		(fp_poly
			(pts
				(xy -0.8636 -0.8636) (xy -0.8636 79.6036) (xy -0.8636 79.629) (xy 5.9436 79.629) (xy 5.9436 79.6036)
				(xy 5.9436 -0.8636) (xy 5.9436 -0.889) (xy -0.8636 -0.889)
			)
			(stroke
				(width 0)
				(type default)
			)
			(fill no)
			(layer "B.CrtYd")
		)
		(fp_rect
			(start -2.135124 -4.560062)
			(end 7.21487 83.300062)
			(stroke
				(width 0)
				(type default)
			)
			(fill no)
			(layer "F.CrtYd")
		)
		(fp_line
			(start -2.135124 -4.560062)
			(end 7.215124 -4.560062)
			(stroke
				(width 0.1)
				(type default)
			)
			(layer "F.Fab")
		)
		(fp_line
			(start -2.135124 83.300062)
			(end -2.135124 -4.560062)
			(stroke
				(width 0.1)
				(type default)
			)
			(layer "F.Fab")
		)
		(fp_line
			(start 7.215124 -4.560062)
			(end 7.215124 83.300062)
			(stroke
				(width 0.1)
				(type default)
			)
			(layer "F.Fab")
		)
		(fp_line
			(start 7.215124 83.300062)
			(end -2.135124 83.300062)
			(stroke
				(width 0.1)
				(type default)
			)
			(layer "F.Fab")
		)
		(fp_text user "32"
			(at -3.83159 78.970124 0)
			(unlocked yes)
			(layer "F.SilkS")
			(effects
				(font
					(size 0.7874 0.5842)
					(thickness 0.1524)
				)
				(justify left)
			)
		)
		(fp_text user "1"
			(at -3.299206 -1.063752 0)
			(unlocked yes)
			(layer "F.SilkS")
			(effects
				(font
					(size 0.7874 0.5842)
					(thickness 0.1524)
				)
				(justify left)
			)
		)
		(fp_text user "33"
			(at 7.548626 82.342482 0)
			(unlocked yes)
			(layer "F.SilkS")
			(effects
				(font
					(size 0.7874 0.5842)
					(thickness 0.1524)
				)
				(justify left)
			)
		)
		(fp_text user "64"
			(at 7.602728 -0.1905 0)
			(unlocked yes)
			(layer "F.SilkS")
			(effects
				(font
					(size 0.7874 0.5842)
					(thickness 0.1524)
				)
				(justify left)
			)
		)
		(fp_text user "1"
			(at -1.714246 -0.92456 0)
			(unlocked yes)
			(layer "B.SilkS")
			(effects
				(font
					(size 0.7874 0.5842)
					(thickness 0.1524)
				)
				(justify left mirror)
			)
		)
		(fp_text user "32"
			(at -0.789432 79.774796 0)
			(unlocked yes)
			(layer "B.SilkS")
			(effects
				(font
					(size 0.7874 0.5842)
					(thickness 0.1524)
				)
				(justify left mirror)
			)
		)
		(fp_text user "64"
			(at 5.867146 -1.71323 0)
			(unlocked yes)
			(layer "B.SilkS")
			(effects
				(font
					(size 0.7874 0.5842)
					(thickness 0.1524)
				)
				(justify left mirror)
			)
		)
		(fp_text user "33"
			(at 5.969508 82.246216 0)
			(unlocked yes)
			(layer "B.SilkS")
			(effects
				(font
					(size 0.7874 0.5842)
					(thickness 0.1524)
				)
				(justify left mirror)
			)
		)
		(pad "1" thru_hole rect
			(at 0 0 270)
			(size 1.6256 1.6256)
			(drill 1.1176)
			(layers "*.Cu" "*.Mask")
			(remove_unused_layers no)
			(net "P12V")
			(clearance 0)
			(padstack
				(mode front_inner_back)
				(layer "Inner"
					(shape circle)
					(size 1.6256 1.6256)
					(clearance 0)
				)
				(layer "B.Cu"
					(shape rect)
					(size 1.6256 1.6256)
					(clearance 0)
				)
			)
		)
		(pad "2" thru_hole circle
			(at 0 2.54 270)
			(size 1.6256 1.6256)
			(drill 1.1176)
			(layers "*.Cu" "*.Mask")
			(remove_unused_layers no)
			(net "P12V")
			(clearance 0)
		)
		(pad "3" thru_hole circle
			(at 0 5.08 270)
			(size 1.6256 1.6256)
			(drill 1.1176)
			(layers "*.Cu" "*.Mask")
			(remove_unused_layers no)
			(net "P12V")
			(clearance 0)
		)
		(pad "4" thru_hole circle
			(at 0 7.62 270)
			(size 1.6256 1.6256)
			(drill 1.1176)
			(layers "*.Cu" "*.Mask")
			(remove_unused_layers no)
			(net "P12V")
			(clearance 0)
		)
		(pad "5" thru_hole circle
			(at 0 10.16 270)
			(size 1.6256 1.6256)
			(drill 1.1176)
			(layers "*.Cu" "*.Mask")
			(remove_unused_layers no)
			(net "P12V")
			(clearance 0)
		)
		(pad "6" thru_hole circle
			(at 0 12.7 270)
			(size 1.6256 1.6256)
			(drill 1.1176)
			(layers "*.Cu" "*.Mask")
			(remove_unused_layers no)
			(net "P12V")
			(clearance 0)
		)
		(pad "7" thru_hole circle
			(at 0 15.24 270)
			(size 1.6256 1.6256)
			(drill 1.1176)
			(layers "*.Cu" "*.Mask")
			(remove_unused_layers no)
			(net "P12V")
			(clearance 0)
		)
		(pad "8" thru_hole circle
			(at 0 17.78 270)
			(size 1.6256 1.6256)
			(drill 1.1176)
			(layers "*.Cu" "*.Mask")
			(remove_unused_layers no)
			(net "P12V")
			(clearance 0)
		)
		(pad "9" thru_hole circle
			(at 0 20.32 270)
			(size 1.6256 1.6256)
			(drill 1.1176)
			(layers "*.Cu" "*.Mask")
			(remove_unused_layers no)
			(net "P12V")
			(clearance 0)
		)
		(pad "10" thru_hole circle
			(at 0 22.86 270)
			(size 1.6256 1.6256)
			(drill 1.1176)
			(layers "*.Cu" "*.Mask")
			(remove_unused_layers no)
			(net "P12V")
			(clearance 0)
		)
		(pad "11" thru_hole circle
			(at 0 25.4 270)
			(size 1.6256 1.6256)
			(drill 1.1176)
			(layers "*.Cu" "*.Mask")
			(remove_unused_layers no)
			(net "P12V")
			(clearance 0)
		)
		(pad "12" thru_hole circle
			(at 0 27.94 270)
			(size 1.6256 1.6256)
			(drill 1.1176)
			(layers "*.Cu" "*.Mask")
			(remove_unused_layers no)
			(net "P12V")
			(clearance 0)
		)
		(pad "13" thru_hole circle
			(at 0 30.48 270)
			(size 1.6256 1.6256)
			(drill 1.1176)
			(layers "*.Cu" "*.Mask")
			(remove_unused_layers no)
			(net "GND")
			(clearance 0)
		)
		(pad "14" thru_hole circle
			(at 0 33.02 270)
			(size 1.6256 1.6256)
			(drill 1.1176)
			(layers "*.Cu" "*.Mask")
			(remove_unused_layers no)
			(net "GND")
			(clearance 0)
		)
		(pad "15" thru_hole circle
			(at 0 35.56 270)
			(size 1.6256 1.6256)
			(drill 1.1176)
			(layers "*.Cu" "*.Mask")
			(remove_unused_layers no)
			(net "GND")
			(clearance 0)
		)
		(pad "16" thru_hole circle
			(at 0 38.1 270)
			(size 1.6256 1.6256)
			(drill 1.1176)
			(layers "*.Cu" "*.Mask")
			(remove_unused_layers no)
			(net "GND")
			(clearance 0)
		)
		(pad "17" thru_hole circle
			(at 0 40.64 270)
			(size 1.6256 1.6256)
			(drill 1.1176)
			(layers "*.Cu" "*.Mask")
			(remove_unused_layers no)
			(net "GND")
			(clearance 0)
		)
		(pad "18" thru_hole circle
			(at 0 43.18 270)
			(size 1.6256 1.6256)
			(drill 1.1176)
			(layers "*.Cu" "*.Mask")
			(remove_unused_layers no)
			(net "GND")
			(clearance 0)
		)
		(pad "19" thru_hole circle
			(at 0 45.72 270)
			(size 1.6256 1.6256)
			(drill 1.1176)
			(layers "*.Cu" "*.Mask")
			(remove_unused_layers no)
			(net "GND")
			(clearance 0)
		)
		(pad "20" thru_hole circle
			(at 0 48.26 270)
			(size 1.6256 1.6256)
			(drill 1.1176)
			(layers "*.Cu" "*.Mask")
			(remove_unused_layers no)
			(net "GND")
			(clearance 0)
		)
		(pad "21" thru_hole circle
			(at 0 50.8 270)
			(size 1.6256 1.6256)
			(drill 1.1176)
			(layers "*.Cu" "*.Mask")
			(remove_unused_layers no)
			(net "GND")
			(clearance 0)
		)
		(pad "22" thru_hole circle
			(at 0 53.34 270)
			(size 1.6256 1.6256)
			(drill 1.1176)
			(layers "*.Cu" "*.Mask")
			(remove_unused_layers no)
			(net "GND")
			(clearance 0)
		)
		(pad "23" thru_hole circle
			(at 0 55.88 270)
			(size 1.6256 1.6256)
			(drill 1.1176)
			(layers "*.Cu" "*.Mask")
			(remove_unused_layers no)
			(net "GND")
			(clearance 0)
		)
		(pad "24" thru_hole circle
			(at 0 58.42 270)
			(size 1.6256 1.6256)
			(drill 1.1176)
			(layers "*.Cu" "*.Mask")
			(remove_unused_layers no)
			(net "GND")
			(clearance 0)
		)
		(pad "25" thru_hole circle
			(at 0 60.96 270)
			(size 1.6256 1.6256)
			(drill 1.1176)
			(layers "*.Cu" "*.Mask")
			(remove_unused_layers no)
			(net "Net_401")
			(clearance 0)
		)
		(pad "26" thru_hole circle
			(at 0 63.5 270)
			(size 1.6256 1.6256)
			(drill 1.1176)
			(layers "*.Cu" "*.Mask")
			(remove_unused_layers no)
			(net "PSU4_REMOTE_N")
			(clearance 0)
		)
		(pad "27" thru_hole circle
			(at 0 66.04 270)
			(size 1.6256 1.6256)
			(drill 1.1176)
			(layers "*.Cu" "*.Mask")
			(remove_unused_layers no)
			(net "PSU4_AC_OK")
			(clearance 0)
		)
		(pad "28" thru_hole circle
			(at 0 68.58 270)
			(size 1.6256 1.6256)
			(drill 1.1176)
			(layers "*.Cu" "*.Mask")
			(remove_unused_layers no)
			(net "PSU4_CSAHRE")
			(clearance 0)
		)
		(pad "29" thru_hole circle
			(at 0 71.12 270)
			(size 1.6256 1.6256)
			(drill 1.1176)
			(layers "*.Cu" "*.Mask")
			(remove_unused_layers no)
			(net "PSU4_PS_ON_N")
			(clearance 0)
		)
		(pad "30" thru_hole circle
			(at 0 73.66 270)
			(size 1.6256 1.6256)
			(drill 1.1176)
			(layers "*.Cu" "*.Mask")
			(remove_unused_layers no)
			(net "PSU4_PS_KILL")
			(clearance 0)
		)
		(pad "31" thru_hole circle
			(at 0 76.2 270)
			(size 1.6256 1.6256)
			(drill 1.1176)
			(layers "*.Cu" "*.Mask")
			(remove_unused_layers no)
			(net "PSU4_RESET")
			(clearance 0)
		)
		(pad "32" thru_hole circle
			(at 0 78.74 270)
			(size 1.6256 1.6256)
			(drill 1.1176)
			(layers "*.Cu" "*.Mask")
			(remove_unused_layers no)
			(net "PSU_ALERT_N")
			(clearance 0)
		)
		(pad "33" thru_hole circle
			(at 5.08 78.74 270)
			(size 1.6256 1.6256)
			(drill 1.1176)
			(layers "*.Cu" "*.Mask")
			(remove_unused_layers no)
			(net "I2C_PSU2_SDA")
			(clearance 0)
		)
		(pad "34" thru_hole circle
			(at 5.08 76.2 270)
			(size 1.6256 1.6256)
			(drill 1.1176)
			(layers "*.Cu" "*.Mask")
			(remove_unused_layers no)
			(net "Net_402")
			(clearance 0)
		)
		(pad "35" thru_hole circle
			(at 5.08 73.66 270)
			(size 1.6256 1.6256)
			(drill 1.1176)
			(layers "*.Cu" "*.Mask")
			(remove_unused_layers no)
			(net "I2C_PSU2_SCL")
			(clearance 0)
		)
		(pad "36" thru_hole circle
			(at 5.08 71.12 270)
			(size 1.6256 1.6256)
			(drill 1.1176)
			(layers "*.Cu" "*.Mask")
			(remove_unused_layers no)
			(net "PSU4_RETURN")
			(clearance 0)
		)
		(pad "37" thru_hole circle
			(at 5.08 68.58 270)
			(size 1.6256 1.6256)
			(drill 1.1176)
			(layers "*.Cu" "*.Mask")
			(remove_unused_layers no)
			(net "PSU4_DC_OK")
			(clearance 0)
		)
		(pad "38" thru_hole circle
			(at 5.08 66.04 270)
			(size 1.6256 1.6256)
			(drill 1.1176)
			(layers "*.Cu" "*.Mask")
			(remove_unused_layers no)
			(net "PSU4_AD0")
			(clearance 0)
		)
		(pad "39" thru_hole circle
			(at 5.08 63.5 270)
			(size 1.6256 1.6256)
			(drill 1.1176)
			(layers "*.Cu" "*.Mask")
			(remove_unused_layers no)
			(net "P12V_STBY")
			(clearance 0)
		)
		(pad "40" thru_hole circle
			(at 5.08 60.96 270)
			(size 1.6256 1.6256)
			(drill 1.1176)
			(layers "*.Cu" "*.Mask")
			(remove_unused_layers no)
			(net "PSU4_REMOTE_P")
			(clearance 0)
		)
		(pad "41" thru_hole circle
			(at 5.08 58.42 270)
			(size 1.6256 1.6256)
			(drill 1.1176)
			(layers "*.Cu" "*.Mask")
			(remove_unused_layers no)
			(net "GND")
			(clearance 0)
		)
		(pad "42" thru_hole circle
			(at 5.08 55.88 270)
			(size 1.6256 1.6256)
			(drill 1.1176)
			(layers "*.Cu" "*.Mask")
			(remove_unused_layers no)
			(net "GND")
			(clearance 0)
		)
		(pad "43" thru_hole circle
			(at 5.08 53.34 270)
			(size 1.6256 1.6256)
			(drill 1.1176)
			(layers "*.Cu" "*.Mask")
			(remove_unused_layers no)
			(net "GND")
			(clearance 0)
		)
		(pad "44" thru_hole circle
			(at 5.08 50.8 270)
			(size 1.6256 1.6256)
			(drill 1.1176)
			(layers "*.Cu" "*.Mask")
			(remove_unused_layers no)
			(net "GND")
			(clearance 0)
		)
		(pad "45" thru_hole circle
			(at 5.08 48.26 270)
			(size 1.6256 1.6256)
			(drill 1.1176)
			(layers "*.Cu" "*.Mask")
			(remove_unused_layers no)
			(net "GND")
			(clearance 0)
		)
		(pad "46" thru_hole circle
			(at 5.08 45.72 270)
			(size 1.6256 1.6256)
			(drill 1.1176)
			(layers "*.Cu" "*.Mask")
			(remove_unused_layers no)
			(net "GND")
			(clearance 0)
		)
		(pad "47" thru_hole circle
			(at 5.08 43.18 270)
			(size 1.6256 1.6256)
			(drill 1.1176)
			(layers "*.Cu" "*.Mask")
			(remove_unused_layers no)
			(net "GND")
			(clearance 0)
		)
		(pad "48" thru_hole circle
			(at 5.08 40.64 270)
			(size 1.6256 1.6256)
			(drill 1.1176)
			(layers "*.Cu" "*.Mask")
			(remove_unused_layers no)
			(net "GND")
			(clearance 0)
		)
		(pad "49" thru_hole circle
			(at 5.08 38.1 270)
			(size 1.6256 1.6256)
			(drill 1.1176)
			(layers "*.Cu" "*.Mask")
			(remove_unused_layers no)
			(net "GND")
			(clearance 0)
		)
		(pad "50" thru_hole circle
			(at 5.08 35.56 270)
			(size 1.6256 1.6256)
			(drill 1.1176)
			(layers "*.Cu" "*.Mask")
			(remove_unused_layers no)
			(net "GND")
			(clearance 0)
		)
		(pad "51" thru_hole circle
			(at 5.08 33.02 270)
			(size 1.6256 1.6256)
			(drill 1.1176)
			(layers "*.Cu" "*.Mask")
			(remove_unused_layers no)
			(net "GND")
			(clearance 0)
		)
		(pad "52" thru_hole circle
			(at 5.08 30.48 270)
			(size 1.6256 1.6256)
			(drill 1.1176)
			(layers "*.Cu" "*.Mask")
			(remove_unused_layers no)
			(net "GND")
			(clearance 0)
		)
		(pad "53" thru_hole circle
			(at 5.08 27.94 270)
			(size 1.6256 1.6256)
			(drill 1.1176)
			(layers "*.Cu" "*.Mask")
			(remove_unused_layers no)
			(net "P12V")
			(clearance 0)
		)
		(pad "54" thru_hole circle
			(at 5.08 25.4 270)
			(size 1.6256 1.6256)
			(drill 1.1176)
			(layers "*.Cu" "*.Mask")
			(remove_unused_layers no)
			(net "P12V")
			(clearance 0)
		)
		(pad "55" thru_hole circle
			(at 5.08 22.86 270)
			(size 1.6256 1.6256)
			(drill 1.1176)
			(layers "*.Cu" "*.Mask")
			(remove_unused_layers no)
			(net "P12V")
			(clearance 0)
		)
		(pad "56" thru_hole circle
			(at 5.08 20.32 270)
			(size 1.6256 1.6256)
			(drill 1.1176)
			(layers "*.Cu" "*.Mask")
			(remove_unused_layers no)
			(net "P12V")
			(clearance 0)
		)
		(pad "57" thru_hole circle
			(at 5.08 17.78 270)
			(size 1.6256 1.6256)
			(drill 1.1176)
			(layers "*.Cu" "*.Mask")
			(remove_unused_layers no)
			(net "P12V")
			(clearance 0)
		)
		(pad "58" thru_hole circle
			(at 5.08 15.24 270)
			(size 1.6256 1.6256)
			(drill 1.1176)
			(layers "*.Cu" "*.Mask")
			(remove_unused_layers no)
			(net "P12V")
			(clearance 0)
		)
		(pad "59" thru_hole circle
			(at 5.08 12.7 270)
			(size 1.6256 1.6256)
			(drill 1.1176)
			(layers "*.Cu" "*.Mask")
			(remove_unused_layers no)
			(net "P12V")
			(clearance 0)
		)
		(pad "60" thru_hole circle
			(at 5.08 10.16 270)
			(size 1.6256 1.6256)
			(drill 1.1176)
			(layers "*.Cu" "*.Mask")
			(remove_unused_layers no)
			(net "P12V")
			(clearance 0)
		)
		(pad "61" thru_hole circle
			(at 5.08 7.62 270)
			(size 1.6256 1.6256)
			(drill 1.1176)
			(layers "*.Cu" "*.Mask")
			(remove_unused_layers no)
			(net "P12V")
			(clearance 0)
		)
		(pad "62" thru_hole circle
			(at 5.08 5.08 270)
			(size 1.6256 1.6256)
			(drill 1.1176)
			(layers "*.Cu" "*.Mask")
			(remove_unused_layers no)
			(net "P12V")
			(clearance 0)
		)
		(pad "63" thru_hole circle
			(at 5.08 2.54 270)
			(size 1.6256 1.6256)
			(drill 1.1176)
			(layers "*.Cu" "*.Mask")
			(remove_unused_layers no)
			(net "P12V")
			(clearance 0)
		)
		(pad "64" thru_hole circle
			(at 5.08 0 270)
			(size 1.6256 1.6256)
			(drill 1.1176)
			(layers "*.Cu" "*.Mask")
			(remove_unused_layers no)
			(net "P12V")
			(clearance 0)
		)
	)
)
